(kicad_pcb
	(version 20260206)
	(generator "pcbnew")
	(generator_version "10.0")
	(general
		(thickness 1.6)
		(legacy_teardrops no)
	)
	(paper "A4")
	(title_block
		(title "03242023_DA0F0TMBIJ0_F0T_Motherboard_J_brd_V01_OCP.brd")
		(comment 1 "Grand Teton / footprints 5445-5451 of 6105")
	)
	(layers
		(0 "F.Cu" signal "TOP")
		(4 "In1.Cu" signal "GND")
		(6 "In2.Cu" signal "IN1")
		(8 "In3.Cu" signal "GND1")
		(10 "In4.Cu" signal "IN2")
		(12 "In5.Cu" signal "GND2")
		(14 "In6.Cu" signal "IN3")
		(16 "In7.Cu" signal "GND3")
		(18 "In8.Cu" signal "VCC")
		(20 "In9.Cu" signal "VCC1")
		(22 "In10.Cu" signal "GND4")
		(24 "In11.Cu" signal "IN4")
		(26 "In12.Cu" signal "GND5")
		(28 "In13.Cu" signal "IN5")
		(30 "In14.Cu" signal "GND6")
		(32 "In15.Cu" signal "IN6")
		(34 "In16.Cu" signal "GND7")
		(2 "B.Cu" signal "BOTTOM")
		(9 "F.Adhes" user "F.Adhesive")
		(11 "B.Adhes" user "B.Adhesive")
		(13 "F.Paste" user "Package Geometry/Pastemask Top")
		(15 "B.Paste" user "Package Geometry/Pastemask Bottom")
		(5 "F.SilkS" user "Ref Des/Silkscreen Top")
		(7 "B.SilkS" user "Ref Des/Silkscreen Bottom")
		(1 "F.Mask" user "Board Geometry/Soldermask Top")
		(3 "B.Mask" user "Board Geometry/Soldermask Bottom")
		(17 "Dwgs.User" user "User.Drawings")
		(19 "Cmts.User" user "User.Comments")
		(21 "Eco1.User" user "User.Eco1")
		(23 "Eco2.User" user "User.Eco2")
		(25 "Edge.Cuts" user "Board Geometry/Outline")
		(27 "Margin" user)
		(31 "F.CrtYd" user "Package Geometry/Place Bound Top")
		(29 "B.CrtYd" user "Package Geometry/Place Bound Bottom")
		(35 "F.Fab" user "Ref Des/Assembly Top")
		(33 "B.Fab" user "Ref Des/Assembly Bottom")
	)
	(footprint ""
		(layer "B.Cu")
		(at 301.356014 -319.263776 180)
		(property "Reference" "C2"
			(at 0 0 0)
			(layer "B.SilkS")
			(hide yes)
			(effects
				(font
					(size 1.27 1.27)
				)
				(justify mirror)
			)
		)
		(property "Value" ""
			(at 0 0 0)
			(layer "B.Fab")
			(effects
				(font
					(size 1.27 1.27)
				)
				(justify mirror)
			)
		)
		(duplicate_pad_numbers_are_jumpers no)
		(fp_line
			(start 0.7874 0.4064)
			(end 0.7874 -0.4064)
			(stroke
				(width 0.1524)
				(type default)
			)
			(layer "B.SilkS")
		)
		(fp_line
			(start 0.7874 -0.4064)
			(end -0.7874 -0.4064)
			(stroke
				(width 0.1524)
				(type default)
			)
			(layer "B.SilkS")
		)
		(fp_line
			(start -0.7874 0.4064)
			(end 0.7874 0.4064)
			(stroke
				(width 0.1524)
				(type default)
			)
			(layer "B.SilkS")
		)
		(fp_line
			(start -0.7874 -0.4064)
			(end -0.7874 0.4064)
			(stroke
				(width 0.1524)
				(type default)
			)
			(layer "B.SilkS")
		)
		(fp_line
			(start 0.67945 0.3048)
			(end 0.67945 -0.305054)
			(stroke
				(width 0.1)
				(type default)
			)
			(layer "B.Fab")
		)
		(fp_line
			(start 0.67945 -0.305054)
			(end 0.12065 -0.305054)
			(stroke
				(width 0.1)
				(type default)
			)
			(layer "B.Fab")
		)
		(fp_line
			(start 0.12065 0.3048)
			(end 0.67945 0.3048)
			(stroke
				(width 0.1)
				(type default)
			)
			(layer "B.Fab")
		)
		(fp_line
			(start 0.12065 0.2794)
			(end 0.12065 0.3048)
			(stroke
				(width 0.1)
				(type default)
			)
			(layer "B.Fab")
		)
		(fp_line
			(start 0.12065 -0.2794)
			(end -0.12065 -0.2794)
			(stroke
				(width 0.1)
				(type default)
			)
			(layer "B.Fab")
		)
		(fp_line
			(start 0.12065 -0.305054)
			(end 0.12065 -0.2794)
			(stroke
				(width 0.1)
				(type default)
			)
			(layer "B.Fab")
		)
		(fp_line
			(start -0.120396 0.3048)
			(end -0.120396 0.2794)
			(stroke
				(width 0.1)
				(type default)
			)
			(layer "B.Fab")
		)
		(fp_line
			(start -0.120396 0.2794)
			(end 0.12065 0.2794)
			(stroke
				(width 0.1)
				(type default)
			)
			(layer "B.Fab")
		)
		(fp_line
			(start -0.12065 -0.2794)
			(end -0.12065 -0.3048)
			(stroke
				(width 0.1)
				(type default)
			)
			(layer "B.Fab")
		)
		(fp_line
			(start -0.12065 -0.3048)
			(end -0.67945 -0.3048)
			(stroke
				(width 0.1)
				(type default)
			)
			(layer "B.Fab")
		)
		(fp_line
			(start -0.67945 0.3048)
			(end -0.120396 0.3048)
			(stroke
				(width 0.1)
				(type default)
			)
			(layer "B.Fab")
		)
		(fp_line
			(start -0.67945 -0.3048)
			(end -0.67945 0.3048)
			(stroke
				(width 0.1)
				(type default)
			)
			(layer "B.Fab")
		)
		(pad "1" smd circle
			(at 0.40005 0)
			(size 0 0)
			(layers "B.Cu" "B.Mask" "B.Paste")
			(net "P3V3_AUX")
		)
		(pad "2" smd circle
			(at -0.40005 0)
			(size 0 0)
			(layers "B.Cu" "B.Mask" "B.Paste")
			(net "GND")
		)
	)
	(footprint ""
		(layer "B.Cu")
		(at 106.437938 -236.008164)
		(property "Reference" "C1353"
			(at 0 0 0)
			(layer "B.SilkS")
			(hide yes)
			(effects
				(font
					(size 1.27 1.27)
				)
				(justify mirror)
			)
		)
		(property "Value" ""
			(at 0 0 0)
			(layer "B.Fab")
			(effects
				(font
					(size 1.27 1.27)
				)
				(justify mirror)
			)
		)
		(duplicate_pad_numbers_are_jumpers no)
		(fp_line
			(start -0.7874 -0.4064)
			(end -0.7874 0.4064)
			(stroke
				(width 0.1524)
				(type default)
			)
			(layer "B.SilkS")
		)
		(fp_line
			(start -0.7874 0.4064)
			(end 0.7874 0.4064)
			(stroke
				(width 0.1524)
				(type default)
			)
			(layer "B.SilkS")
		)
		(fp_line
			(start 0.7874 -0.4064)
			(end -0.7874 -0.4064)
			(stroke
				(width 0.1524)
				(type default)
			)
			(layer "B.SilkS")
		)
		(fp_line
			(start 0.7874 0.4064)
			(end 0.7874 -0.4064)
			(stroke
				(width 0.1524)
				(type default)
			)
			(layer "B.SilkS")
		)
		(fp_line
			(start -0.67945 -0.3048)
			(end -0.67945 0.3048)
			(stroke
				(width 0.1)
				(type default)
			)
			(layer "B.Fab")
		)
		(fp_line
			(start -0.67945 0.3048)
			(end -0.120396 0.3048)
			(stroke
				(width 0.1)
				(type default)
			)
			(layer "B.Fab")
		)
		(fp_line
			(start -0.12065 -0.3048)
			(end -0.67945 -0.3048)
			(stroke
				(width 0.1)
				(type default)
			)
			(layer "B.Fab")
		)
		(fp_line
			(start -0.12065 -0.2794)
			(end -0.12065 -0.3048)
			(stroke
				(width 0.1)
				(type default)
			)
			(layer "B.Fab")
		)
		(fp_line
			(start -0.120396 0.2794)
			(end 0.12065 0.2794)
			(stroke
				(width 0.1)
				(type default)
			)
			(layer "B.Fab")
		)
		(fp_line
			(start -0.120396 0.3048)
			(end -0.120396 0.2794)
			(stroke
				(width 0.1)
				(type default)
			)
			(layer "B.Fab")
		)
		(fp_line
			(start 0.12065 -0.305054)
			(end 0.12065 -0.2794)
			(stroke
				(width 0.1)
				(type default)
			)
			(layer "B.Fab")
		)
		(fp_line
			(start 0.12065 -0.2794)
			(end -0.12065 -0.2794)
			(stroke
				(width 0.1)
				(type default)
			)
			(layer "B.Fab")
		)
		(fp_line
			(start 0.12065 0.2794)
			(end 0.12065 0.3048)
			(stroke
				(width 0.1)
				(type default)
			)
			(layer "B.Fab")
		)
		(fp_line
			(start 0.12065 0.3048)
			(end 0.67945 0.3048)
			(stroke
				(width 0.1)
				(type default)
			)
			(layer "B.Fab")
		)
		(fp_line
			(start 0.67945 -0.305054)
			(end 0.12065 -0.305054)
			(stroke
				(width 0.1)
				(type default)
			)
			(layer "B.Fab")
		)
		(fp_line
			(start 0.67945 0.3048)
			(end 0.67945 -0.305054)
			(stroke
				(width 0.1)
				(type default)
			)
			(layer "B.Fab")
		)
		(pad "1" smd circle
			(at 0.40005 0 180)
			(size 0 0)
			(layers "B.Cu" "B.Mask" "B.Paste")
			(net "PVNN_MAIN_CPU1")
		)
		(pad "2" smd circle
			(at -0.40005 0 180)
			(size 0 0)
			(layers "B.Cu" "B.Mask" "B.Paste")
			(net "GND")
		)
	)
	(footprint ""
		(layer "B.Cu")
		(at 118.137178 -241.14379 -90)
		(property "Reference" "C337"
			(at 0 0 90)
			(layer "B.SilkS")
			(hide yes)
			(effects
				(font
					(size 1.27 1.27)
				)
				(justify mirror)
			)
		)
		(property "Value" ""
			(at 0 0 90)
			(layer "B.Fab")
			(effects
				(font
					(size 1.27 1.27)
				)
				(justify mirror)
			)
		)
		(duplicate_pad_numbers_are_jumpers no)
		(fp_line
			(start -1.524 0.762)
			(end 1.524 0.762)
			(stroke
				(width 0.1524)
				(type default)
			)
			(layer "B.SilkS")
		)
		(fp_line
			(start 1.524 0.762)
			(end 1.524 -0.762)
			(stroke
				(width 0.1524)
				(type default)
			)
			(layer "B.SilkS")
		)
		(fp_line
			(start -1.524 -0.762)
			(end -1.524 0.762)
			(stroke
				(width 0.1524)
				(type default)
			)
			(layer "B.SilkS")
		)
		(fp_line
			(start 1.524 -0.762)
			(end -1.524 -0.762)
			(stroke
				(width 0.1524)
				(type default)
			)
			(layer "B.SilkS")
		)
		(fp_line
			(start -1.1049 0.724916)
			(end -1.1049 -0.724916)
			(stroke
				(width 0.1)
				(type default)
			)
			(layer "B.Fab")
		)
		(fp_line
			(start 1.1049 0.724916)
			(end -1.1049 0.724916)
			(stroke
				(width 0.1)
				(type default)
			)
			(layer "B.Fab")
		)
		(fp_line
			(start -1.1049 -0.724916)
			(end 1.1049 -0.724916)
			(stroke
				(width 0.1)
				(type default)
			)
			(layer "B.Fab")
		)
		(fp_line
			(start 1.1049 -0.724916)
			(end 1.1049 0.724916)
			(stroke
				(width 0.1)
				(type default)
			)
			(layer "B.Fab")
		)
		(pad "1" smd rect
			(at 0.889 0 270)
			(size 1.016 1.27)
			(layers "B.Cu" "B.Mask" "B.Paste")
			(net "PVCCIN_CPU1")
		)
		(pad "2" smd rect
			(at -0.889 0 270)
			(size 1.016 1.27)
			(layers "B.Cu" "B.Mask" "B.Paste")
			(net "GND")
		)
	)
	(footprint ""
		(layer "B.Cu")
		(at 45.018706 -344.935556 -90)
		(property "Reference" "PC1207_P1_4"
			(at 0 0 90)
			(layer "B.SilkS")
			(hide yes)
			(effects
				(font
					(size 1.27 1.27)
				)
				(justify mirror)
			)
		)
		(property "Value" ""
			(at 0 0 90)
			(layer "B.Fab")
			(effects
				(font
					(size 1.27 1.27)
				)
				(justify mirror)
			)
		)
		(duplicate_pad_numbers_are_jumpers no)
		(fp_line
			(start -1.524 0.762)
			(end 1.524 0.762)
			(stroke
				(width 0.1524)
				(type default)
			)
			(layer "B.SilkS")
		)
		(fp_line
			(start 1.524 0.762)
			(end 1.524 -0.762)
			(stroke
				(width 0.1524)
				(type default)
			)
			(layer "B.SilkS")
		)
		(fp_line
			(start -1.524 -0.762)
			(end -1.524 0.762)
			(stroke
				(width 0.1524)
				(type default)
			)
			(layer "B.SilkS")
		)
		(fp_line
			(start 1.524 -0.762)
			(end -1.524 -0.762)
			(stroke
				(width 0.1524)
				(type default)
			)
			(layer "B.SilkS")
		)
		(fp_line
			(start -1.1049 0.724916)
			(end -1.1049 -0.724916)
			(stroke
				(width 0.1)
				(type default)
			)
			(layer "B.Fab")
		)
		(fp_line
			(start 1.1049 0.724916)
			(end -1.1049 0.724916)
			(stroke
				(width 0.1)
				(type default)
			)
			(layer "B.Fab")
		)
		(fp_line
			(start -1.1049 -0.724916)
			(end 1.1049 -0.724916)
			(stroke
				(width 0.1)
				(type default)
			)
			(layer "B.Fab")
		)
		(fp_line
			(start 1.1049 -0.724916)
			(end 1.1049 0.724916)
			(stroke
				(width 0.1)
				(type default)
			)
			(layer "B.Fab")
		)
		(pad "1" smd rect
			(at 0.889 0 270)
			(size 1.016 1.27)
			(layers "B.Cu" "B.Mask" "B.Paste")
			(net "PVCCFA_EHV_FIVRA_CPU1")
		)
		(pad "2" smd rect
			(at -0.889 0 270)
			(size 1.016 1.27)
			(layers "B.Cu" "B.Mask" "B.Paste")
			(net "GND")
		)
	)
	(footprint ""
		(layer "B.Cu")
		(at 456.003406 -319.232026 180)
		(property "Reference" "R2735"
			(at 0 0 0)
			(layer "B.SilkS")
			(hide yes)
			(effects
				(font
					(size 1.27 1.27)
				)
				(justify mirror)
			)
		)
		(property "Value" ""
			(at 0 0 0)
			(layer "B.Fab")
			(effects
				(font
					(size 1.27 1.27)
				)
				(justify mirror)
			)
		)
		(duplicate_pad_numbers_are_jumpers no)
		(fp_line
			(start 0.7874 0.4064)
			(end 0.7874 -0.4064)
			(stroke
				(width 0.1524)
				(type default)
			)
			(layer "B.SilkS")
		)
		(fp_line
			(start 0.7874 -0.4064)
			(end -0.7874 -0.4064)
			(stroke
				(width 0.1524)
				(type default)
			)
			(layer "B.SilkS")
		)
		(fp_line
			(start -0.7874 0.4064)
			(end 0.7874 0.4064)
			(stroke
				(width 0.1524)
				(type default)
			)
			(layer "B.SilkS")
		)
		(fp_line
			(start -0.7874 -0.4064)
			(end -0.7874 0.4064)
			(stroke
				(width 0.1524)
				(type default)
			)
			(layer "B.SilkS")
		)
		(fp_line
			(start 0.67945 0.3048)
			(end 0.67945 -0.305054)
			(stroke
				(width 0.1)
				(type default)
			)
			(layer "B.Fab")
		)
		(fp_line
			(start 0.67945 -0.305054)
			(end 0.12065 -0.305054)
			(stroke
				(width 0.1)
				(type default)
			)
			(layer "B.Fab")
		)
		(fp_line
			(start 0.12065 0.3048)
			(end 0.67945 0.3048)
			(stroke
				(width 0.1)
				(type default)
			)
			(layer "B.Fab")
		)
		(fp_line
			(start 0.12065 0.2794)
			(end 0.12065 0.3048)
			(stroke
				(width 0.1)
				(type default)
			)
			(layer "B.Fab")
		)
		(fp_line
			(start 0.12065 -0.2794)
			(end -0.12065 -0.2794)
			(stroke
				(width 0.1)
				(type default)
			)
			(layer "B.Fab")
		)
		(fp_line
			(start 0.12065 -0.305054)
			(end 0.12065 -0.2794)
			(stroke
				(width 0.1)
				(type default)
			)
			(layer "B.Fab")
		)
		(fp_line
			(start -0.120396 0.3048)
			(end -0.120396 0.2794)
			(stroke
				(width 0.1)
				(type default)
			)
			(layer "B.Fab")
		)
		(fp_line
			(start -0.120396 0.2794)
			(end 0.12065 0.2794)
			(stroke
				(width 0.1)
				(type default)
			)
			(layer "B.Fab")
		)
		(fp_line
			(start -0.12065 -0.2794)
			(end -0.12065 -0.3048)
			(stroke
				(width 0.1)
				(type default)
			)
			(layer "B.Fab")
		)
		(fp_line
			(start -0.12065 -0.3048)
			(end -0.67945 -0.3048)
			(stroke
				(width 0.1)
				(type default)
			)
			(layer "B.Fab")
		)
		(fp_line
			(start -0.67945 0.3048)
			(end -0.120396 0.3048)
			(stroke
				(width 0.1)
				(type default)
			)
			(layer "B.Fab")
		)
		(fp_line
			(start -0.67945 -0.3048)
			(end -0.67945 0.3048)
			(stroke
				(width 0.1)
				(type default)
			)
			(layer "B.Fab")
		)
		(pad "1" smd circle
			(at 0.40005 0)
			(size 0 0)
			(layers "B.Cu" "B.Mask" "B.Paste")
			(net "PWRGD_CHH_CPU0_DIMM2")
		)
		(pad "2" smd circle
			(at -0.40005 0)
			(size 0 0)
			(layers "B.Cu" "B.Mask" "B.Paste")
			(net "PWRGD_FAIL_CPU0_GH")
		)
	)
	(footprint ""
		(layer "B.Cu")
		(at 293.812214 -319.263776 180)
		(property "Reference" "C11"
			(at 0 0 0)
			(layer "B.SilkS")
			(hide yes)
			(effects
				(font
					(size 1.27 1.27)
				)
				(justify mirror)
			)
		)
		(property "Value" ""
			(at 0 0 0)
			(layer "B.Fab")
			(effects
				(font
					(size 1.27 1.27)
				)
				(justify mirror)
			)
		)
		(duplicate_pad_numbers_are_jumpers no)
		(fp_line
			(start 0.7874 0.4064)
			(end 0.7874 -0.4064)
			(stroke
				(width 0.1524)
				(type default)
			)
			(layer "B.SilkS")
		)
		(fp_line
			(start 0.7874 -0.4064)
			(end -0.7874 -0.4064)
			(stroke
				(width 0.1524)
				(type default)
			)
			(layer "B.SilkS")
		)
		(fp_line
			(start -0.7874 0.4064)
			(end 0.7874 0.4064)
			(stroke
				(width 0.1524)
				(type default)
			)
			(layer "B.SilkS")
		)
		(fp_line
			(start -0.7874 -0.4064)
			(end -0.7874 0.4064)
			(stroke
				(width 0.1524)
				(type default)
			)
			(layer "B.SilkS")
		)
		(fp_line
			(start 0.67945 0.3048)
			(end 0.67945 -0.305054)
			(stroke
				(width 0.1)
				(type default)
			)
			(layer "B.Fab")
		)
		(fp_line
			(start 0.67945 -0.305054)
			(end 0.12065 -0.305054)
			(stroke
				(width 0.1)
				(type default)
			)
			(layer "B.Fab")
		)
		(fp_line
			(start 0.12065 0.3048)
			(end 0.67945 0.3048)
			(stroke
				(width 0.1)
				(type default)
			)
			(layer "B.Fab")
		)
		(fp_line
			(start 0.12065 0.2794)
			(end 0.12065 0.3048)
			(stroke
				(width 0.1)
				(type default)
			)
			(layer "B.Fab")
		)
		(fp_line
			(start 0.12065 -0.2794)
			(end -0.12065 -0.2794)
			(stroke
				(width 0.1)
				(type default)
			)
			(layer "B.Fab")
		)
		(fp_line
			(start 0.12065 -0.305054)
			(end 0.12065 -0.2794)
			(stroke
				(width 0.1)
				(type default)
			)
			(layer "B.Fab")
		)
		(fp_line
			(start -0.120396 0.3048)
			(end -0.120396 0.2794)
			(stroke
				(width 0.1)
				(type default)
			)
			(layer "B.Fab")
		)
		(fp_line
			(start -0.120396 0.2794)
			(end 0.12065 0.2794)
			(stroke
				(width 0.1)
				(type default)
			)
			(layer "B.Fab")
		)
		(fp_line
			(start -0.12065 -0.2794)
			(end -0.12065 -0.3048)
			(stroke
				(width 0.1)
				(type default)
			)
			(layer "B.Fab")
		)
		(fp_line
			(start -0.12065 -0.3048)
			(end -0.67945 -0.3048)
			(stroke
				(width 0.1)
				(type default)
			)
			(layer "B.Fab")
		)
		(fp_line
			(start -0.67945 0.3048)
			(end -0.120396 0.3048)
			(stroke
				(width 0.1)
				(type default)
			)
			(layer "B.Fab")
		)
		(fp_line
			(start -0.67945 -0.3048)
			(end -0.67945 0.3048)
			(stroke
				(width 0.1)
				(type default)
			)
			(layer "B.Fab")
		)
		(pad "1" smd circle
			(at 0.40005 0)
			(size 0 0)
			(layers "B.Cu" "B.Mask" "B.Paste")
			(net "P3V3_AUX")
		)
		(pad "2" smd circle
			(at -0.40005 0)
			(size 0 0)
			(layers "B.Cu" "B.Mask" "B.Paste")
			(net "GND")
		)
	)
	(footprint ""
		(layer "B.Cu")
		(at 175.44288 -123.948698 -90)
		(property "Reference" "C1939"
			(at 0 0 90)
			(layer "B.SilkS")
			(hide yes)
			(effects
				(font
					(size 1.27 1.27)
				)
				(justify mirror)
			)
		)
		(property "Value" ""
			(at 0 0 90)
			(layer "B.Fab")
			(effects
				(font
					(size 1.27 1.27)
				)
				(justify mirror)
			)
		)
		(duplicate_pad_numbers_are_jumpers no)
		(fp_line
			(start -0.7874 0.4064)
			(end 0.7874 0.4064)
			(stroke
				(width 0.1524)
				(type default)
			)
			(layer "B.SilkS")
		)
		(fp_line
			(start 0.7874 0.4064)
			(end 0.7874 -0.4064)
			(stroke
				(width 0.1524)
				(type default)
			)
			(layer "B.SilkS")
		)
		(fp_line
			(start -0.7874 -0.4064)
			(end -0.7874 0.4064)
			(stroke
				(width 0.1524)
				(type default)
			)
			(layer "B.SilkS")
		)
		(fp_line
			(start 0.7874 -0.4064)
			(end -0.7874 -0.4064)
			(stroke
				(width 0.1524)
				(type default)
			)
			(layer "B.SilkS")
		)
		(fp_line
			(start -0.67945 0.3048)
			(end -0.120396 0.3048)
			(stroke
				(width 0.1)
				(type default)
			)
			(layer "B.Fab")
		)
		(fp_line
			(start -0.120396 0.3048)
			(end -0.120396 0.2794)
			(stroke
				(width 0.1)
				(type default)
			)
			(layer "B.Fab")
		)
		(fp_line
			(start 0.12065 0.3048)
			(end 0.67945 0.3048)
			(stroke
				(width 0.1)
				(type default)
			)
			(layer "B.Fab")
		)
		(fp_line
			(start 0.67945 0.3048)
			(end 0.67945 -0.305054)
			(stroke
				(width 0.1)
				(type default)
			)
			(layer "B.Fab")
		)
		(fp_line
			(start -0.120396 0.2794)
			(end 0.12065 0.2794)
			(stroke
				(width 0.1)
				(type default)
			)
			(layer "B.Fab")
		)
		(fp_line
			(start 0.12065 0.2794)
			(end 0.12065 0.3048)
			(stroke
				(width 0.1)
				(type default)
			)
			(layer "B.Fab")
		)
		(fp_line
			(start -0.12065 -0.2794)
			(end -0.12065 -0.3048)
			(stroke
				(width 0.1)
				(type default)
			)
			(layer "B.Fab")
		)
		(fp_line
			(start 0.12065 -0.2794)
			(end -0.12065 -0.2794)
			(stroke
				(width 0.1)
				(type default)
			)
			(layer "B.Fab")
		)
		(fp_line
			(start -0.67945 -0.3048)
			(end -0.67945 0.3048)
			(stroke
				(width 0.1)
				(type default)
			)
			(layer "B.Fab")
		)
		(fp_line
			(start -0.12065 -0.3048)
			(end -0.67945 -0.3048)
			(stroke
				(width 0.1)
				(type default)
			)
			(layer "B.Fab")
		)
		(fp_line
			(start 0.12065 -0.305054)
			(end 0.12065 -0.2794)
			(stroke
				(width 0.1)
				(type default)
			)
			(layer "B.Fab")
		)
		(fp_line
			(start 0.67945 -0.305054)
			(end 0.12065 -0.305054)
			(stroke
				(width 0.1)
				(type default)
			)
			(layer "B.Fab")
		)
		(pad "1" smd circle
			(at 0.40005 0 90)
			(size 0 0)
			(layers "B.Cu" "B.Mask" "B.Paste")
			(net "P3V3_AUX_FPGA_VCCIO1")
		)
		(pad "2" smd circle
			(at -0.40005 0 90)
			(size 0 0)
			(layers "B.Cu" "B.Mask" "B.Paste")
			(net "GND")
		)
	)
)
